(kicad_pcb
	(version 20260206)
	(generator "pcbnew")
	(generator_version "10.0")
	(general
		(thickness 1.6)
		(legacy_teardrops no)
	)
	(paper "A4")
	(title_block
		(title "dpb — 14545-sa.0730WZS0815.brd")
		(comment 1 "Honey Badger (Wiwynn) / footprints 339-343 of 1066")
	)
	(layers
		(0 "F.Cu" signal "TOP")
		(4 "In1.Cu" signal "L2GND")
		(6 "In2.Cu" signal "L3")
		(8 "In3.Cu" signal "L4VCC")
		(10 "In4.Cu" signal "L5VCC")
		(12 "In5.Cu" signal "L6")
		(14 "In6.Cu" signal "L7GND")
		(2 "B.Cu" signal "BOTTOM")
		(9 "F.Adhes" user "F.Adhesive")
		(11 "B.Adhes" user "B.Adhesive")
		(13 "F.Paste" user "Package Geometry/Pastemask Top")
		(15 "B.Paste" user "Package Geometry/Pastemask Bottom")
		(5 "F.SilkS" user "Ref Des/Silkscreen Top")
		(7 "B.SilkS" user "Ref Des/Silkscreen Bottom")
		(1 "F.Mask" user "Board Geometry/Soldermask Top")
		(3 "B.Mask" user "Board Geometry/Soldermask Bottom")
		(17 "Dwgs.User" user "User.Drawings")
		(19 "Cmts.User" user "User.Comments")
		(21 "Eco1.User" user "User.Eco1")
		(23 "Eco2.User" user "User.Eco2")
		(25 "Edge.Cuts" user "Board Geometry/Outline")
		(27 "Margin" user)
		(31 "F.CrtYd" user "Package Geometry/Place Bound Top")
		(29 "B.CrtYd" user "Package Geometry/Place Bound Bottom")
		(35 "F.Fab" user "Ref Des/Assembly Top")
		(33 "B.Fab" user "Ref Des/Assembly Bottom")
	)
	(footprint ""
		(layer "F.Cu")
		(at 45.338746 -245.7577 90)
		(property "Reference" "R202"
			(at 0 0 90)
			(layer "F.SilkS")
			(hide yes)
			(effects
				(font
					(size 1.27 1.27)
				)
			)
		)
		(property "Value" "0R2J-2-GP"
			(at 0.064008 -3.993896 90)
			(unlocked yes)
			(layer "F.Fab")
			(hide yes)
			(effects
				(font
					(size 1.016 1.016)
					(thickness 0.1524)
				)
			)
		)
		(property "Device Type" "R402H16"
			(at 0.064008 -5.517896 90)
			(unlocked yes)
			(layer "F.Fab")
			(hide yes)
			(effects
				(font
					(size 1.016 1.016)
					(thickness 0.1524)
				)
			)
		)
		(duplicate_pad_numbers_are_jumpers no)
		(fp_line
			(start 0.508 -0.9398)
			(end -0.508 -0.9398)
			(stroke
				(width 0.1524)
				(type default)
			)
			(layer "F.SilkS")
		)
		(fp_line
			(start -0.508 -0.9398)
			(end -0.508 0.9398)
			(stroke
				(width 0.1524)
				(type default)
			)
			(layer "F.SilkS")
		)
		(fp_rect
			(start -0.508 0.9398)
			(end 0.508 -0.9398)
			(stroke
				(width 0)
				(type default)
			)
			(fill no)
			(layer "F.CrtYd")
		)
		(fp_rect
			(start -0.508 0.9398)
			(end 0.508 -0.9398)
			(stroke
				(width 0)
				(type default)
			)
			(fill no)
			(layer "F.Fab")
		)
		(pad "1" smd custom
			(at 0 -0.4445 90)
			(size 0.1397 0.1397)
			(layers "F.Cu" "F.Mask" "F.Paste")
			(net "FLT_NET_HDD7")
			(options
				(clearance outline)
				(anchor circle)
			)
			(primitives
				(gr_poly
					(pts
						(arc
							(start -0.1778 -0.2794)
							(mid -0.249642 -0.249642)
							(end -0.2794 -0.1778)
						)
						(arc
							(start -0.2794 0.1778)
							(mid -0.249642 0.249642)
							(end -0.1778 0.2794)
						)
						(arc
							(start 0.1778 0.2794)
							(mid 0.249642 0.249642)
							(end 0.2794 0.1778)
						)
						(arc
							(start 0.2794 -0.1778)
							(mid 0.249642 -0.249642)
							(end 0.1778 -0.2794)
						)
					)
					(width 0)
					(fill yes)
				)
			)
		)
		(pad "2" smd custom
			(at 0 0.4445 90)
			(size 0.1397 0.1397)
			(layers "F.Cu" "F.Mask" "F.Paste")
			(net "FLT_HDD7_DRIVE")
			(options
				(clearance outline)
				(anchor circle)
			)
			(primitives
				(gr_poly
					(pts
						(arc
							(start -0.1778 -0.2794)
							(mid -0.249642 -0.249642)
							(end -0.2794 -0.1778)
						)
						(arc
							(start -0.2794 0.1778)
							(mid -0.249642 0.249642)
							(end -0.1778 0.2794)
						)
						(arc
							(start 0.1778 0.2794)
							(mid 0.249642 0.249642)
							(end 0.2794 0.1778)
						)
						(arc
							(start 0.2794 -0.1778)
							(mid 0.249642 -0.249642)
							(end 0.1778 -0.2794)
						)
					)
					(width 0)
					(fill yes)
				)
			)
		)
	)
	(footprint ""
		(layer "F.Cu")
		(at 45.974 -105.283 90)
		(property "Reference" "D28"
			(at 0 0 90)
			(layer "F.SilkS")
			(hide yes)
			(effects
				(font
					(size 1.27 1.27)
				)
			)
		)
		(property "Value" "RB551V30-1-GP"
			(at 0 -6.7818 90)
			(unlocked yes)
			(layer "F.Fab")
			(hide yes)
			(effects
				(font
					(size 1.016 1.016)
					(thickness 0.1524)
				)
			)
		)
		(property "Device Type" "SOD323AKH44"
			(at 0 -8.6868 90)
			(unlocked yes)
			(layer "F.Fab")
			(hide yes)
			(effects
				(font
					(size 1.016 1.016)
					(thickness 0.1524)
				)
			)
		)
		(duplicate_pad_numbers_are_jumpers no)
		(fp_line
			(start 0.889 -1.9304)
			(end 0.889 2.159)
			(stroke
				(width 0.1524)
				(type default)
			)
			(layer "F.SilkS")
		)
		(fp_line
			(start -0.889 -1.9304)
			(end 0.889 -1.9304)
			(stroke
				(width 0.1524)
				(type default)
			)
			(layer "F.SilkS")
		)
		(fp_line
			(start 0.762 2.0574)
			(end -0.762 2.0574)
			(stroke
				(width 0.508)
				(type default)
			)
			(layer "F.SilkS")
		)
		(fp_line
			(start 0.889 2.159)
			(end -0.889 2.159)
			(stroke
				(width 0.1524)
				(type default)
			)
			(layer "F.SilkS")
		)
		(fp_line
			(start -0.889 2.159)
			(end -0.889 -1.9304)
			(stroke
				(width 0.1524)
				(type default)
			)
			(layer "F.SilkS")
		)
		(fp_rect
			(start -1.016 2.3114)
			(end 1.016 -2.0066)
			(stroke
				(width 0)
				(type default)
			)
			(fill no)
			(layer "F.CrtYd")
		)
		(fp_poly
			(pts
				(xy -1.016 -2.0066) (xy 1.016 -2.0066) (xy 1.016 2.3114) (xy -1.016 2.3114)
			)
			(stroke
				(width 0)
				(type default)
			)
			(fill no)
			(layer "F.Fab")
		)
		(pad "A" smd rect
			(at 0 -1.143 90)
			(size 0.5588 1.016)
			(layers "F.Cu" "F.Mask" "F.Paste")
			(net "SW_HDD13_R")
		)
		(pad "K" smd rect
			(at 0 1.143 90)
			(size 0.5588 1.016)
			(layers "F.Cu" "F.Mask" "F.Paste")
			(net "SW_HDD13_N")
		)
	)
	(footprint ""
		(layer "F.Cu")
		(at 197.230746 -491.5027 -90)
		(property "Reference" "R424"
			(at 0 0 270)
			(layer "F.SilkS")
			(hide yes)
			(effects
				(font
					(size 1.27 1.27)
				)
			)
		)
		(property "Value" "4K7R2J-2-GP"
			(at 0.064008 -3.993896 270)
			(unlocked yes)
			(layer "F.Fab")
			(hide yes)
			(effects
				(font
					(size 1.016 1.016)
					(thickness 0.1524)
				)
			)
		)
		(property "Device Type" "R402H16"
			(at 0.064008 -5.517896 270)
			(unlocked yes)
			(layer "F.Fab")
			(hide yes)
			(effects
				(font
					(size 1.016 1.016)
					(thickness 0.1524)
				)
			)
		)
		(duplicate_pad_numbers_are_jumpers no)
		(fp_line
			(start -0.508 -0.9398)
			(end -0.508 0.9398)
			(stroke
				(width 0.1524)
				(type default)
			)
			(layer "F.SilkS")
		)
		(fp_line
			(start 0.508 -0.9398)
			(end -0.508 -0.9398)
			(stroke
				(width 0.1524)
				(type default)
			)
			(layer "F.SilkS")
		)
		(fp_rect
			(start -0.508 0.9398)
			(end 0.508 -0.9398)
			(stroke
				(width 0)
				(type default)
			)
			(fill no)
			(layer "F.CrtYd")
		)
		(fp_rect
			(start -0.508 0.9398)
			(end 0.508 -0.9398)
			(stroke
				(width 0)
				(type default)
			)
			(fill no)
			(layer "F.Fab")
		)
		(pad "1" smd custom
			(at 0 -0.4445 270)
			(size 0.1397 0.1397)
			(layers "F.Cu" "F.Mask" "F.Paste")
			(net "P3V3")
			(options
				(clearance outline)
				(anchor circle)
			)
			(primitives
				(gr_poly
					(pts
						(arc
							(start -0.1778 -0.2794)
							(mid -0.249642 -0.249642)
							(end -0.2794 -0.1778)
						)
						(arc
							(start -0.2794 0.1778)
							(mid -0.249642 0.249642)
							(end -0.1778 0.2794)
						)
						(arc
							(start 0.1778 0.2794)
							(mid 0.249642 0.249642)
							(end 0.2794 0.1778)
						)
						(arc
							(start 0.2794 -0.1778)
							(mid 0.249642 -0.249642)
							(end 0.1778 -0.2794)
						)
					)
					(width 0)
					(fill yes)
				)
			)
		)
		(pad "2" smd custom
			(at 0 0.4445 270)
			(size 0.1397 0.1397)
			(layers "F.Cu" "F.Mask" "F.Paste")
			(net "SAS_EXP_B_PWR0")
			(options
				(clearance outline)
				(anchor circle)
			)
			(primitives
				(gr_poly
					(pts
						(arc
							(start -0.1778 -0.2794)
							(mid -0.249642 -0.249642)
							(end -0.2794 -0.1778)
						)
						(arc
							(start -0.2794 0.1778)
							(mid -0.249642 0.249642)
							(end -0.1778 0.2794)
						)
						(arc
							(start 0.1778 0.2794)
							(mid 0.249642 0.249642)
							(end 0.2794 0.1778)
						)
						(arc
							(start 0.2794 -0.1778)
							(mid 0.249642 -0.249642)
							(end 0.1778 -0.2794)
						)
					)
					(width 0)
					(fill yes)
				)
			)
		)
	)
	(footprint ""
		(layer "F.Cu")
		(at 16.306546 -468.0204 -90)
		(property "Reference" "Q44"
			(at 0 0 270)
			(layer "F.SilkS")
			(hide yes)
			(effects
				(font
					(size 1.27 1.27)
				)
			)
		)
		(property "Value" "PMBS3904-1-GP"
			(at 0 -9.0932 270)
			(unlocked yes)
			(layer "F.Fab")
			(hide yes)
			(effects
				(font
					(size 1.016 1.016)
					(thickness 0.1524)
				)
			)
		)
		(property "Device Type" "SOT-23-10H44"
			(at 0 -10.6172 270)
			(unlocked yes)
			(layer "F.Fab")
			(hide yes)
			(effects
				(font
					(size 1.016 1.016)
					(thickness 0.1524)
				)
			)
		)
		(duplicate_pad_numbers_are_jumpers no)
		(fp_line
			(start -1.279144 2.15265)
			(end -0.701294 2.15265)
			(stroke
				(width 0.0127)
				(type default)
			)
			(layer "F.SilkS")
		)
		(fp_line
			(start -0.71628 2.15265)
			(end -1.26492 2.15265)
			(stroke
				(width 0.0127)
				(type default)
			)
			(layer "F.SilkS")
		)
		(fp_line
			(start -1.279398 2.152142)
			(end -0.9906 1.86309)
			(stroke
				(width 0.0127)
				(type default)
			)
			(layer "F.SilkS")
		)
		(fp_line
			(start -0.719074 2.145538)
			(end -1.265936 2.14122)
			(stroke
				(width 0.0127)
				(type default)
			)
			(layer "F.SilkS")
		)
		(fp_line
			(start -1.260856 2.1336)
			(end -0.720344 2.1336)
			(stroke
				(width 0.0127)
				(type default)
			)
			(layer "F.SilkS")
		)
		(fp_line
			(start -1.251458 2.124202)
			(end -0.729996 2.124202)
			(stroke
				(width 0.0127)
				(type default)
			)
			(layer "F.SilkS")
		)
		(fp_line
			(start -1.241806 2.11455)
			(end -0.739394 2.11455)
			(stroke
				(width 0.0127)
				(type default)
			)
			(layer "F.SilkS")
		)
		(fp_line
			(start -1.232408 2.105152)
			(end -0.749046 2.105152)
			(stroke
				(width 0.0127)
				(type default)
			)
			(layer "F.SilkS")
		)
		(fp_line
			(start -1.222756 2.0955)
			(end -0.758444 2.0955)
			(stroke
				(width 0.0127)
				(type default)
			)
			(layer "F.SilkS")
		)
		(fp_line
			(start -1.213358 2.086102)
			(end -0.768096 2.086102)
			(stroke
				(width 0.0127)
				(type default)
			)
			(layer "F.SilkS")
		)
		(fp_line
			(start -1.203706 2.07645)
			(end -0.777494 2.07645)
			(stroke
				(width 0.0127)
				(type default)
			)
			(layer "F.SilkS")
		)
		(fp_line
			(start -1.194308 2.067052)
			(end -0.787146 2.067052)
			(stroke
				(width 0.0127)
				(type default)
			)
			(layer "F.SilkS")
		)
		(fp_line
			(start -1.184656 2.0574)
			(end -0.796544 2.0574)
			(stroke
				(width 0.0127)
				(type default)
			)
			(layer "F.SilkS")
		)
		(fp_line
			(start -1.175258 2.048002)
			(end -0.806196 2.048002)
			(stroke
				(width 0.0127)
				(type default)
			)
			(layer "F.SilkS")
		)
		(fp_line
			(start -1.165606 2.03835)
			(end -0.815594 2.03835)
			(stroke
				(width 0.0127)
				(type default)
			)
			(layer "F.SilkS")
		)
		(fp_line
			(start -1.156208 2.028952)
			(end -0.825246 2.028952)
			(stroke
				(width 0.0127)
				(type default)
			)
			(layer "F.SilkS")
		)
		(fp_line
			(start -1.146556 2.0193)
			(end -0.834644 2.0193)
			(stroke
				(width 0.0127)
				(type default)
			)
			(layer "F.SilkS")
		)
		(fp_line
			(start -1.137158 2.009902)
			(end -0.844296 2.009902)
			(stroke
				(width 0.0127)
				(type default)
			)
			(layer "F.SilkS")
		)
		(fp_line
			(start -1.127506 2.00025)
			(end -0.853694 2.00025)
			(stroke
				(width 0.0127)
				(type default)
			)
			(layer "F.SilkS")
		)
		(fp_line
			(start -1.118108 1.990852)
			(end -0.863346 1.990852)
			(stroke
				(width 0.0127)
				(type default)
			)
			(layer "F.SilkS")
		)
		(fp_line
			(start -1.108456 1.9812)
			(end -0.872744 1.9812)
			(stroke
				(width 0.0127)
				(type default)
			)
			(layer "F.SilkS")
		)
		(fp_line
			(start -1.099058 1.971802)
			(end -0.882396 1.971802)
			(stroke
				(width 0.0127)
				(type default)
			)
			(layer "F.SilkS")
		)
		(fp_line
			(start -1.089406 1.96215)
			(end -0.891794 1.96215)
			(stroke
				(width 0.0127)
				(type default)
			)
			(layer "F.SilkS")
		)
		(fp_line
			(start -1.080008 1.952752)
			(end -0.901446 1.952752)
			(stroke
				(width 0.0127)
				(type default)
			)
			(layer "F.SilkS")
		)
		(fp_line
			(start -1.070356 1.9431)
			(end -0.910844 1.9431)
			(stroke
				(width 0.0127)
				(type default)
			)
			(layer "F.SilkS")
		)
		(fp_line
			(start -1.060958 1.933702)
			(end -0.920496 1.933702)
			(stroke
				(width 0.0127)
				(type default)
			)
			(layer "F.SilkS")
		)
		(fp_line
			(start -1.051306 1.92405)
			(end -0.929894 1.92405)
			(stroke
				(width 0.0127)
				(type default)
			)
			(layer "F.SilkS")
		)
		(fp_line
			(start -1.041908 1.914652)
			(end -0.939546 1.914652)
			(stroke
				(width 0.0127)
				(type default)
			)
			(layer "F.SilkS")
		)
		(fp_line
			(start -1.032256 1.905)
			(end -0.948944 1.905)
			(stroke
				(width 0.0127)
				(type default)
			)
			(layer "F.SilkS")
		)
		(fp_line
			(start -1.022858 1.895602)
			(end -0.958596 1.895602)
			(stroke
				(width 0.0127)
				(type default)
			)
			(layer "F.SilkS")
		)
		(fp_line
			(start -1.013206 1.88595)
			(end -0.967994 1.88595)
			(stroke
				(width 0.0127)
				(type default)
			)
			(layer "F.SilkS")
		)
		(fp_line
			(start -1.7526 1.8796)
			(end -1.7526 0.9906)
			(stroke
				(width 0.3302)
				(type default)
			)
			(layer "F.SilkS")
		)
		(fp_line
			(start -0.635 1.8796)
			(end -1.7526 1.8796)
			(stroke
				(width 0.3302)
				(type default)
			)
			(layer "F.SilkS")
		)
		(fp_line
			(start -1.003808 1.876552)
			(end -0.977646 1.876552)
			(stroke
				(width 0.0127)
				(type default)
			)
			(layer "F.SilkS")
		)
		(fp_line
			(start -0.994156 1.8669)
			(end -0.987044 1.8669)
			(stroke
				(width 0.0127)
				(type default)
			)
			(layer "F.SilkS")
		)
		(fp_line
			(start -0.9906 1.86309)
			(end -0.701294 2.15265)
			(stroke
				(width 0.0127)
				(type default)
			)
			(layer "F.SilkS")
		)
		(fp_line
			(start -1.651 1.778)
			(end 1.651 1.778)
			(stroke
				(width 0.1524)
				(type default)
			)
			(layer "F.SilkS")
		)
		(fp_line
			(start 1.651 1.778)
			(end 1.651 -1.778)
			(stroke
				(width 0.1524)
				(type default)
			)
			(layer "F.SilkS")
		)
		(fp_line
			(start -1.651 -1.778)
			(end -1.651 1.778)
			(stroke
				(width 0.1524)
				(type default)
			)
			(layer "F.SilkS")
		)
		(fp_line
			(start 1.651 -1.778)
			(end -1.651 -1.778)
			(stroke
				(width 0.1524)
				(type default)
			)
			(layer "F.SilkS")
		)
		(fp_poly
			(pts
				(xy -1.285748 2.159) (xy -1.285748 1.8796) (xy -1.778 1.8796) (xy -1.778 -1.8796) (xy 1.778 -1.8796)
				(xy 1.778 1.8796) (xy -0.694944 1.8796) (xy -0.694944 2.159)
			)
			(stroke
				(width 0)
				(type default)
			)
			(fill no)
			(layer "F.CrtYd")
		)
		(fp_poly
			(pts
				(xy -1.285748 2.159) (xy -1.285748 1.8796) (xy -1.778 1.8796) (xy -1.778 -1.8796) (xy 1.778 -1.8796)
				(xy 1.778 1.8796) (xy -0.694944 1.8796) (xy -0.694944 2.159)
			)
			(stroke
				(width 0)
				(type default)
			)
			(fill no)
			(layer "F.Fab")
		)
		(pad "1" smd rect
			(at -0.98425 0.9525 270)
			(size 0.762 1.143)
			(layers "F.Cu" "F.Mask" "F.Paste")
			(net "FLT_HDD10_B")
		)
		(pad "2" smd rect
			(at 0.98425 0.9525 270)
			(size 0.762 1.143)
			(layers "F.Cu" "F.Mask" "F.Paste")
			(net "GND")
		)
		(pad "3" smd rect
			(at 0 -0.9525 270)
			(size 0.762 1.143)
			(layers "F.Cu" "F.Mask" "F.Paste")
			(net "DRIVE_ACT_10")
		)
	)
	(footprint ""
		(layer "F.Cu")
		(at 67.055492 -76.863956 -90)
		(property "Reference" "Q19"
			(at 0 0 270)
			(layer "F.SilkS")
			(hide yes)
			(effects
				(font
					(size 1.27 1.27)
				)
			)
		)
		(property "Value" "AO4406AL-GP"
			(at -3.707384 -1.5367 270)
			(unlocked yes)
			(layer "F.Fab")
			(hide yes)
			(effects
				(font
					(size 1.016 1.016)
					(thickness 0.1524)
				)
			)
		)
		(property "Device Type" "SOIC8H69"
			(at -3.707384 -3.0607 270)
			(unlocked yes)
			(layer "F.Fab")
			(hide yes)
			(effects
				(font
					(size 1.016 1.016)
					(thickness 0.1524)
				)
			)
		)
		(duplicate_pad_numbers_are_jumpers no)
		(fp_line
			(start -2.6289 3.4417)
			(end -2.6289 1.4732)
			(stroke
				(width 0.381)
				(type default)
			)
			(layer "F.SilkS")
		)
		(fp_line
			(start -2.7432 1.4224)
			(end -2.6416 1.4224)
			(stroke
				(width 0.1524)
				(type default)
			)
			(layer "F.SilkS")
		)
		(fp_line
			(start -2.7432 1.4224)
			(end 2.1336 1.4224)
			(stroke
				(width 0.1524)
				(type default)
			)
			(layer "F.SilkS")
		)
		(fp_line
			(start 2.1336 1.4224)
			(end 2.1336 -1.4224)
			(stroke
				(width 0.1524)
				(type default)
			)
			(layer "F.SilkS")
		)
		(fp_line
			(start -2.1844 -0.0508)
			(end -2.7178 0.508)
			(stroke
				(width 0.1524)
				(type default)
			)
			(layer "F.SilkS")
		)
		(fp_line
			(start -2.7178 -0.508)
			(end -2.1844 -0.0508)
			(stroke
				(width 0.1524)
				(type default)
			)
			(layer "F.SilkS")
		)
		(fp_line
			(start -2.7432 -1.4224)
			(end -2.7432 1.4224)
			(stroke
				(width 0.1524)
				(type default)
			)
			(layer "F.SilkS")
		)
		(fp_line
			(start 2.1336 -1.4224)
			(end -2.7432 -1.4224)
			(stroke
				(width 0.1524)
				(type default)
			)
			(layer "F.SilkS")
		)
		(fp_poly
			(pts
				(xy -2.2098 -1.4224) (xy -2.2098 1.4224) (xy 2.2098 1.4224) (xy 2.2098 -1.4224)
			)
			(stroke
				(width 0)
				(type default)
			)
			(fill yes)
			(layer "F.SilkS")
		)
		(fp_rect
			(start -2.450084 2.999994)
			(end 2.450084 -2.999994)
			(stroke
				(width 0)
				(type default)
			)
			(fill no)
			(layer "F.CrtYd")
		)
		(fp_poly
			(pts
				(xy -2.8194 3.6322) (xy -2.8194 -3.6322) (xy 2.8194 -3.6322) (xy 2.8194 1.18364) (xy 2.450084 1.18364)
				(xy 2.450084 -2.999994) (xy -2.450084 -2.999994) (xy -2.450084 2.999994) (xy 2.450084 2.999994)
				(xy 2.450084 1.18618) (xy 2.8194 1.18618) (xy 2.8194 3.6322)
			)
			(stroke
				(width 0)
				(type default)
			)
			(fill no)
			(layer "F.CrtYd")
		)
		(fp_rect
			(start -2.8194 3.6322)
			(end 2.8194 -3.6322)
			(stroke
				(width 0)
				(type default)
			)
			(fill no)
			(layer "F.Fab")
		)
		(pad "1" smd rect
			(at -1.905 2.54 270)
			(size 0.635 1.651)
			(layers "F.Cu" "F.Mask" "F.Paste")
			(net "P5V_HDD9")
		)
		(pad "2" smd rect
			(at -0.635 2.54 270)
			(size 0.635 1.651)
			(layers "F.Cu" "F.Mask" "F.Paste")
			(net "P5V_HDD9")
		)
		(pad "3" smd rect
			(at 0.635 2.54 270)
			(size 0.635 1.651)
			(layers "F.Cu" "F.Mask" "F.Paste")
			(net "P5V_HDD9")
		)
		(pad "4" smd rect
			(at 1.905 2.54 270)
			(size 0.635 1.651)
			(layers "F.Cu" "F.Mask" "F.Paste")
			(net "SW_HDD9_P")
		)
		(pad "5" smd rect
			(at 1.905 -2.54 270)
			(size 0.635 1.651)
			(layers "F.Cu" "F.Mask" "F.Paste")
			(net "P5VB")
		)
		(pad "6" smd rect
			(at 0.635 -2.54 270)
			(size 0.635 1.651)
			(layers "F.Cu" "F.Mask" "F.Paste")
			(net "P5VB")
		)
		(pad "7" smd rect
			(at -0.635 -2.54 270)
			(size 0.635 1.651)
			(layers "F.Cu" "F.Mask" "F.Paste")
			(net "P5VB")
		)
		(pad "8" smd rect
			(at -1.905 -2.54 270)
			(size 0.635 1.651)
			(layers "F.Cu" "F.Mask" "F.Paste")
			(net "P5VB")
		)
	)
)
